(kicad_pcb
	(version 20241229)
	(generator "pcbnew")
	(generator_version "9.0")
	(general
		(thickness 1.6)
		(legacy_teardrops no)
	)
	(paper "A4")
	(title_block
		(title "GMSL Deserializer")
		(date "2025-10-09")
		(rev "1.0.4")
		(company "Antmicro Ltd")
		(comment 1 "www.antmicro.com")
		(comment 9 "footprints 32-38 of 235")
	)
	(layers
		(0 "F.Cu" signal)
		(4 "In1.Cu" power)
		(6 "In2.Cu" power)
		(2 "B.Cu" signal)
		(9 "F.Adhes" user "F.Adhesive")
		(11 "B.Adhes" user "B.Adhesive")
		(13 "F.Paste" user)
		(15 "B.Paste" user)
		(5 "F.SilkS" user "F.Silkscreen")
		(7 "B.SilkS" user "B.Silkscreen")
		(1 "F.Mask" user)
		(3 "B.Mask" user)
		(17 "Dwgs.User" user "User.Drawings")
		(19 "Cmts.User" user "User.Comments")
		(21 "Eco1.User" user "User.Eco1")
		(23 "Eco2.User" user "User.Eco2")
		(25 "Edge.Cuts" user)
		(27 "Margin" user)
		(31 "F.CrtYd" user "F.Courtyard")
		(29 "B.CrtYd" user "B.Courtyard")
		(35 "F.Fab" user)
		(33 "B.Fab" user)
	)
	(footprint "antmicro-footprints:C_0402_1005Metric"
		(layer "F.Cu")
		(at 187.706 55.118)
		(descr "Capacitor SMD 0402")
		(tags "capacitor SMD 0402")
		(property "Reference" "C59"
			(at 0.698445 0.413325 0)
			(layer "F.SilkS")
			(effects
				(font
					(size 0.7 0.7)
					(thickness 0.15)
				)
				(justify left bottom)
			)
		)
		(property "Value" "C_1u_0402"
			(at -1.022927 2.155213 0)
			(layer "F.Fab")
			(effects
				(font
					(size 0.7 0.7)
					(thickness 0.15)
				)
				(justify left bottom)
			)
		)
		(property "Datasheet" "https://product.tdk.com/en/search/capacitor/ceramic/mlcc/info?part_no=C1005X6S1A105K050BC"
			(at 0 0 0)
			(layer "F.Fab")
			(hide yes)
			(effects
				(font
					(size 1.27 1.27)
					(thickness 0.15)
				)
			)
		)
		(property "Description" "SMD Multilayer Ceramic Capacitor, 1 µF, 10 V, 0402 [1005 Metric], ± 10%, X6S, C"
			(at 0 0 0)
			(layer "F.Fab")
			(hide yes)
			(effects
				(font
					(size 1.27 1.27)
					(thickness 0.15)
				)
			)
		)
		(property "Author" "Antmicro"
			(at 0 0 0)
			(layer "F.Fab")
			(hide yes)
			(effects
				(font
					(size 1 1)
					(thickness 0.15)
				)
			)
		)
		(property "Dielectric" ""
			(at 0 0 0)
			(layer "F.Fab")
			(hide yes)
			(effects
				(font
					(size 1 1)
					(thickness 0.15)
				)
			)
		)
		(property "License" "Apache-2.0"
			(at 0 0 0)
			(layer "F.Fab")
			(hide yes)
			(effects
				(font
					(size 1 1)
					(thickness 0.15)
				)
			)
		)
		(property "MPN" "C1005X6S1A105K050BC"
			(at 0 0 0)
			(layer "F.Fab")
			(hide yes)
			(effects
				(font
					(size 1 1)
					(thickness 0.15)
				)
			)
		)
		(property "Manufacturer" "TDK"
			(at 0 0 0)
			(layer "F.Fab")
			(hide yes)
			(effects
				(font
					(size 1 1)
					(thickness 0.15)
				)
			)
		)
		(property "Val" "1u"
			(at 0 0 0)
			(layer "F.Fab")
			(hide yes)
			(effects
				(font
					(size 1 1)
					(thickness 0.15)
				)
			)
		)
		(property "Voltage" ""
			(at 0 0 0)
			(layer "F.Fab")
			(hide yes)
			(effects
				(font
					(size 1 1)
					(thickness 0.15)
				)
			)
		)
		(sheetname "/Power/")
		(sheetfile "power.kicad_sch")
		(attr smd)
		(fp_rect
			(start -0.925 -0.47)
			(end 0.925 0.47)
			(stroke
				(width 0.05)
				(type default)
			)
			(fill no)
			(layer "F.CrtYd")
		)
		(fp_line
			(start -0.494 -0.25)
			(end 0.504 -0.25)
			(stroke
				(width 0.15)
				(type solid)
			)
			(layer "F.Fab")
		)
		(fp_line
			(start -0.494 0.248)
			(end -0.494 -0.25)
			(stroke
				(width 0.15)
				(type solid)
			)
			(layer "F.Fab")
		)
		(fp_line
			(start 0.504 -0.25)
			(end 0.504 0.248)
			(stroke
				(width 0.15)
				(type solid)
			)
			(layer "F.Fab")
		)
		(fp_line
			(start 0.504 0.248)
			(end -0.494 0.248)
			(stroke
				(width 0.15)
				(type solid)
			)
			(layer "F.Fab")
		)
		(pad "1" smd roundrect
			(at -0.48 0)
			(size 0.59 0.64)
			(layers "F.Cu" "F.Mask" "F.Paste")
			(roundrect_rratio 0.25)
			(net 1 "GND")
			(pintype "passive")
		)
		(pad "2" smd roundrect
			(at 0.48 0)
			(size 0.59 0.64)
			(layers "F.Cu" "F.Mask" "F.Paste")
			(roundrect_rratio 0.25)
			(net 113 "/Connectors/FFC_5V")
			(pintype "passive")
		)
	)
	(footprint "antmicro-footprints:C_0402_1005Metric"
		(layer "F.Cu")
		(at 130.963 93.078 90)
		(descr "Capacitor SMD 0402")
		(tags "capacitor SMD 0402")
		(property "Reference" "C24"
			(at -0.394 -2.185 90)
			(layer "F.SilkS")
			(effects
				(font
					(size 0.7 0.7)
					(thickness 0.15)
				)
				(justify left bottom)
			)
		)
		(property "Value" "C_22u_0402"
			(at -1.022927 2.155213 90)
			(layer "F.Fab")
			(effects
				(font
					(size 0.7 0.7)
					(thickness 0.15)
				)
				(justify left bottom)
			)
		)
		(property "Datasheet" "https://www.murata.com/products/productdetail?partno=GRM158R60J226ME01%23"
			(at 0 0 90)
			(layer "F.Fab")
			(hide yes)
			(effects
				(font
					(size 1.27 1.27)
					(thickness 0.15)
				)
			)
		)
		(property "Description" "SMD Multilayer Ceramic Capacitor, 22 uF, 4 V, 0402 [1005 Metric], X6S"
			(at 0 0 90)
			(layer "F.Fab")
			(hide yes)
			(effects
				(font
					(size 1.27 1.27)
					(thickness 0.15)
				)
			)
		)
		(property "Author" "Antmicro"
			(at 224.041 -37.885 0)
			(layer "F.Fab")
			(hide yes)
			(effects
				(font
					(size 1 1)
					(thickness 0.15)
				)
			)
		)
		(property "Dielectric" ""
			(at 224.041 -37.885 0)
			(layer "F.Fab")
			(hide yes)
			(effects
				(font
					(size 1 1)
					(thickness 0.15)
				)
			)
		)
		(property "License" "Apache-2.0"
			(at 224.041 -37.885 0)
			(layer "F.Fab")
			(hide yes)
			(effects
				(font
					(size 1 1)
					(thickness 0.15)
				)
			)
		)
		(property "MPN" "GRM158R60J226ME01D"
			(at 224.041 -37.885 0)
			(layer "F.Fab")
			(hide yes)
			(effects
				(font
					(size 1 1)
					(thickness 0.15)
				)
			)
		)
		(property "Manufacturer" "Murata"
			(at 224.041 -37.885 0)
			(layer "F.Fab")
			(hide yes)
			(effects
				(font
					(size 1 1)
					(thickness 0.15)
				)
			)
		)
		(property "Val" "22u"
			(at 224.041 -37.885 0)
			(layer "F.Fab")
			(hide yes)
			(effects
				(font
					(size 1 1)
					(thickness 0.15)
				)
			)
		)
		(property "Voltage" ""
			(at 224.041 -37.885 0)
			(layer "F.Fab")
			(hide yes)
			(effects
				(font
					(size 1 1)
					(thickness 0.15)
				)
			)
		)
		(sheetname "/Power/")
		(sheetfile "power.kicad_sch")
		(attr smd)
		(fp_rect
			(start -0.925 -0.47)
			(end 0.925 0.47)
			(stroke
				(width 0.05)
				(type default)
			)
			(fill no)
			(layer "F.CrtYd")
		)
		(fp_line
			(start 0.504 -0.25)
			(end 0.504 0.248)
			(stroke
				(width 0.15)
				(type solid)
			)
			(layer "F.Fab")
		)
		(fp_line
			(start -0.494 -0.25)
			(end 0.504 -0.25)
			(stroke
				(width 0.15)
				(type solid)
			)
			(layer "F.Fab")
		)
		(fp_line
			(start 0.504 0.248)
			(end -0.494 0.248)
			(stroke
				(width 0.15)
				(type solid)
			)
			(layer "F.Fab")
		)
		(fp_line
			(start -0.494 0.248)
			(end -0.494 -0.25)
			(stroke
				(width 0.15)
				(type solid)
			)
			(layer "F.Fab")
		)
		(pad "1" smd roundrect
			(at -0.48 0 90)
			(size 0.59 0.64)
			(layers "F.Cu" "F.Mask" "F.Paste")
			(roundrect_rratio 0.25)
			(net 1 "GND")
			(pintype "passive")
		)
		(pad "2" smd roundrect
			(at 0.48 0 90)
			(size 0.59 0.64)
			(layers "F.Cu" "F.Mask" "F.Paste")
			(roundrect_rratio 0.25)
			(net 10 "/Power/OUT_1V8")
			(pintype "passive")
		)
	)
	(footprint "antmicro-footprints:R_0402_1005Metric"
		(layer "F.Cu")
		(at 139.192 94.488 180)
		(descr "Resistor SMD 0402")
		(tags "resistor SMD 0402")
		(property "Reference" "R64"
			(at -1.016 0.508 0)
			(layer "F.SilkS")
			(effects
				(font
					(size 0.7 0.7)
					(thickness 0.15)
				)
				(justify left bottom)
			)
		)
		(property "Value" "R_10k_0402"
			(at -1.011843 1.772047 0)
			(layer "F.Fab")
			(effects
				(font
					(size 0.7 0.7)
					(thickness 0.15)
				)
				(justify right bottom)
			)
		)
		(property "Datasheet" "https://www.bourns.com/docs/product-datasheets/cr.pdf"
			(at 0 0 180)
			(layer "F.Fab")
			(hide yes)
			(effects
				(font
					(size 1.27 1.27)
					(thickness 0.15)
				)
			)
		)
		(property "Description" "SMD Chip Resistor, 10 kohm, ± 1%, 62.5 mW, 0402 [1005 Metric], Thick Film, General Purpose"
			(at 0 0 180)
			(layer "F.Fab")
			(hide yes)
			(effects
				(font
					(size 1.27 1.27)
					(thickness 0.15)
				)
			)
		)
		(property "Author" "Antmicro"
			(at 278.384 188.976 0)
			(layer "F.Fab")
			(hide yes)
			(effects
				(font
					(size 1 1)
					(thickness 0.15)
				)
			)
		)
		(property "License" "Apache-2.0"
			(at 278.384 188.976 0)
			(layer "F.Fab")
			(hide yes)
			(effects
				(font
					(size 1 1)
					(thickness 0.15)
				)
			)
		)
		(property "MPN" "CR0402-FX-1002GLF"
			(at 278.384 188.976 0)
			(layer "F.Fab")
			(hide yes)
			(effects
				(font
					(size 1 1)
					(thickness 0.15)
				)
			)
		)
		(property "Manufacturer" "Bourns"
			(at 278.384 188.976 0)
			(layer "F.Fab")
			(hide yes)
			(effects
				(font
					(size 1 1)
					(thickness 0.15)
				)
			)
		)
		(property "Tolerance" "1%"
			(at 278.384 188.976 0)
			(layer "F.Fab")
			(hide yes)
			(effects
				(font
					(size 1 1)
					(thickness 0.15)
				)
			)
		)
		(property "Val" "10k"
			(at 278.384 188.976 0)
			(layer "F.Fab")
			(hide yes)
			(effects
				(font
					(size 1 1)
					(thickness 0.15)
				)
			)
		)
		(sheetname "/Power/")
		(sheetfile "power.kicad_sch")
		(attr smd)
		(fp_rect
			(start -0.925 -0.47)
			(end 0.925 0.47)
			(stroke
				(width 0.05)
				(type default)
			)
			(fill no)
			(layer "F.CrtYd")
		)
		(fp_rect
			(start -0.5 -0.25)
			(end 0.5 0.25)
			(stroke
				(width 0.15)
				(type solid)
			)
			(fill no)
			(layer "F.Fab")
		)
		(pad "1" smd roundrect
			(at -0.48 0 180)
			(size 0.59 0.64)
			(layers "F.Cu" "F.Mask" "F.Paste")
			(roundrect_rratio 0.25)
			(net 1 "GND")
			(pintype "passive")
		)
		(pad "2" smd roundrect
			(at 0.48 0 180)
			(size 0.59 0.64)
			(layers "F.Cu" "F.Mask" "F.Paste")
			(roundrect_rratio 0.25)
			(net 69 "/Power/EN_1V8")
			(pintype "passive")
		)
	)
	(footprint "antmicro-footprints:TP_SMD_0.75mm"
		(layer "F.Cu")
		(at 136.222 84.914)
		(property "Reference" "TP3"
			(at -3.3062 0.3024 0)
			(layer "F.SilkS")
			(hide yes)
			(effects
				(font
					(size 0.7 0.7)
					(thickness 0.15)
				)
				(justify left bottom)
			)
		)
		(property "Value" "TP_0.75mm_SMD"
			(at 0 1.2 0)
			(layer "F.Fab")
			(effects
				(font
					(size 0.7 0.7)
					(thickness 0.15)
				)
				(justify left bottom)
			)
		)
		(property "Description" "SMT test point"
			(at 0 0 0)
			(layer "F.Fab")
			(hide yes)
			(effects
				(font
					(size 1.27 1.27)
					(thickness 0.15)
				)
			)
		)
		(property "Author" "Antmicro"
			(at 0 0 0)
			(layer "F.Fab")
			(hide yes)
			(effects
				(font
					(size 1 1)
					(thickness 0.15)
				)
			)
		)
		(property "License" "Apache-2.0"
			(at 0 0 0)
			(layer "F.Fab")
			(hide yes)
			(effects
				(font
					(size 1 1)
					(thickness 0.15)
				)
			)
		)
		(property "MPN" ""
			(at 0 0 0)
			(layer "F.Fab")
			(hide yes)
			(effects
				(font
					(size 1 1)
					(thickness 0.15)
				)
			)
		)
		(property "Manufacturer" ""
			(at 0 0 0)
			(layer "F.Fab")
			(hide yes)
			(effects
				(font
					(size 1 1)
					(thickness 0.15)
				)
			)
		)
		(sheetname "/Connectors/")
		(sheetfile "connectors.kicad_sch")
		(fp_circle
			(center 0 0)
			(end 0.475 0)
			(stroke
				(width 0.05)
				(type default)
			)
			(fill no)
			(layer "F.CrtYd")
		)
		(pad "1" smd circle
			(at 0 0)
			(size 0.75 0.75)
			(layers "F.Cu" "F.Mask")
			(net 86 "/Connectors/MFP7")
			(pinfunction "1")
			(pintype "passive")
		)
	)
	(footprint "antmicro-footprints:C_0402_1005Metric"
		(layer "F.Cu")
		(at 122.301 66.548 90)
		(descr "Capacitor SMD 0402")
		(tags "capacitor SMD 0402")
		(property "Reference" "C6"
			(at -1.397 -0.635 90)
			(layer "F.SilkS")
			(effects
				(font
					(size 0.7 0.7)
					(thickness 0.15)
				)
				(justify left bottom)
			)
		)
		(property "Value" "C_100n_0402"
			(at -1.022927 2.155213 90)
			(layer "F.Fab")
			(effects
				(font
					(size 0.7 0.7)
					(thickness 0.15)
				)
				(justify left bottom)
			)
		)
		(property "Datasheet" "https://www.murata.com/products/productdetail?partno=GRM155R61H104KE14%23"
			(at 0 0 90)
			(layer "F.Fab")
			(hide yes)
			(effects
				(font
					(size 1.27 1.27)
					(thickness 0.15)
				)
			)
		)
		(property "Description" "SMD Multilayer Ceramic Capacitor, 0.1 µF, 50 V, 0402 [1005 Metric], ± 10%, X5R, GRM Series"
			(at 0 0 90)
			(layer "F.Fab")
			(hide yes)
			(effects
				(font
					(size 1.27 1.27)
					(thickness 0.15)
				)
			)
		)
		(property "Author" "Antmicro"
			(at 188.849 -55.753 0)
			(layer "F.Fab")
			(hide yes)
			(effects
				(font
					(size 1 1)
					(thickness 0.15)
				)
			)
		)
		(property "Dielectric" "X5R"
			(at 188.849 -55.753 0)
			(layer "F.Fab")
			(hide yes)
			(effects
				(font
					(size 1 1)
					(thickness 0.15)
				)
			)
		)
		(property "License" "Apache-2.0"
			(at 188.849 -55.753 0)
			(layer "F.Fab")
			(hide yes)
			(effects
				(font
					(size 1 1)
					(thickness 0.15)
				)
			)
		)
		(property "MPN" "GRM155R61H104KE14D"
			(at 188.849 -55.753 0)
			(layer "F.Fab")
			(hide yes)
			(effects
				(font
					(size 1 1)
					(thickness 0.15)
				)
			)
		)
		(property "Manufacturer" "Murata"
			(at 188.849 -55.753 0)
			(layer "F.Fab")
			(hide yes)
			(effects
				(font
					(size 1 1)
					(thickness 0.15)
				)
			)
		)
		(property "Val" "100n"
			(at 188.849 -55.753 0)
			(layer "F.Fab")
			(hide yes)
			(effects
				(font
					(size 1 1)
					(thickness 0.15)
				)
			)
		)
		(property "Voltage" "50V"
			(at 188.849 -55.753 0)
			(layer "F.Fab")
			(hide yes)
			(effects
				(font
					(size 1 1)
					(thickness 0.15)
				)
			)
		)
		(sheetname "/Power/")
		(sheetfile "power.kicad_sch")
		(attr smd)
		(fp_rect
			(start -0.925 -0.47)
			(end 0.925 0.47)
			(stroke
				(width 0.05)
				(type default)
			)
			(fill no)
			(layer "F.CrtYd")
		)
		(fp_line
			(start 0.504 -0.25)
			(end 0.504 0.248)
			(stroke
				(width 0.15)
				(type solid)
			)
			(layer "F.Fab")
		)
		(fp_line
			(start -0.494 -0.25)
			(end 0.504 -0.25)
			(stroke
				(width 0.15)
				(type solid)
			)
			(layer "F.Fab")
		)
		(fp_line
			(start 0.504 0.248)
			(end -0.494 0.248)
			(stroke
				(width 0.15)
				(type solid)
			)
			(layer "F.Fab")
		)
		(fp_line
			(start -0.494 0.248)
			(end -0.494 -0.25)
			(stroke
				(width 0.15)
				(type solid)
			)
			(layer "F.Fab")
		)
		(pad "1" smd roundrect
			(at -0.48 0 90)
			(size 0.59 0.64)
			(layers "F.Cu" "F.Mask" "F.Paste")
			(roundrect_rratio 0.25)
			(net 1 "GND")
			(pintype "passive")
		)
		(pad "2" smd roundrect
			(at 0.48 0 90)
			(size 0.59 0.64)
			(layers "F.Cu" "F.Mask" "F.Paste")
			(roundrect_rratio 0.25)
			(net 4 "+12V")
			(pintype "passive")
		)
	)
	(footprint "antmicro-footprints:C_0402_1005Metric"
		(layer "F.Cu")
		(at 125.658 74.018 90)
		(descr "Capacitor SMD 0402")
		(tags "capacitor SMD 0402")
		(property "Reference" "C14"
			(at 0.739 1.215 90)
			(layer "F.SilkS")
			(effects
				(font
					(size 0.7 0.7)
					(thickness 0.15)
				)
				(justify left bottom)
			)
		)
		(property "Value" "C_2u2_0402"
			(at -1.022927 2.155213 90)
			(layer "F.Fab")
			(effects
				(font
					(size 0.7 0.7)
					(thickness 0.15)
				)
				(justify left bottom)
			)
		)
		(property "Datasheet" "https://product.tdk.com/en/search/capacitor/ceramic/mlcc/info?part_no=C1005X5R1A225K050BC"
			(at 0 0 90)
			(layer "F.Fab")
			(hide yes)
			(effects
				(font
					(size 1.27 1.27)
					(thickness 0.15)
				)
			)
		)
		(property "Description" "SMD Multilayer Ceramic Capacitor, 2.2 µF, 10 V, 0402 [1005 Metric], ± 10%, X5R, C"
			(at 0 0 90)
			(layer "F.Fab")
			(hide yes)
			(effects
				(font
					(size 1.27 1.27)
					(thickness 0.15)
				)
			)
		)
		(property "Author" "Antmicro"
			(at 199.676 -51.64 0)
			(layer "F.Fab")
			(hide yes)
			(effects
				(font
					(size 1 1)
					(thickness 0.15)
				)
			)
		)
		(property "Dielectric" ""
			(at 199.676 -51.64 0)
			(layer "F.Fab")
			(hide yes)
			(effects
				(font
					(size 1 1)
					(thickness 0.15)
				)
			)
		)
		(property "License" "Apache-2.0"
			(at 199.676 -51.64 0)
			(layer "F.Fab")
			(hide yes)
			(effects
				(font
					(size 1 1)
					(thickness 0.15)
				)
			)
		)
		(property "MPN" "C1005X5R1A225K050BC"
			(at 199.676 -51.64 0)
			(layer "F.Fab")
			(hide yes)
			(effects
				(font
					(size 1 1)
					(thickness 0.15)
				)
			)
		)
		(property "Manufacturer" "TDK"
			(at 199.676 -51.64 0)
			(layer "F.Fab")
			(hide yes)
			(effects
				(font
					(size 1 1)
					(thickness 0.15)
				)
			)
		)
		(property "Val" "2u2"
			(at 199.676 -51.64 0)
			(layer "F.Fab")
			(hide yes)
			(effects
				(font
					(size 1 1)
					(thickness 0.15)
				)
			)
		)
		(property "Voltage" ""
			(at 199.676 -51.64 0)
			(layer "F.Fab")
			(hide yes)
			(effects
				(font
					(size 1 1)
					(thickness 0.15)
				)
			)
		)
		(sheetname "/Power/")
		(sheetfile "power.kicad_sch")
		(attr smd)
		(fp_rect
			(start -0.925 -0.47)
			(end 0.925 0.47)
			(stroke
				(width 0.05)
				(type default)
			)
			(fill no)
			(layer "F.CrtYd")
		)
		(fp_line
			(start 0.504 -0.25)
			(end 0.504 0.248)
			(stroke
				(width 0.15)
				(type solid)
			)
			(layer "F.Fab")
		)
		(fp_line
			(start -0.494 -0.25)
			(end 0.504 -0.25)
			(stroke
				(width 0.15)
				(type solid)
			)
			(layer "F.Fab")
		)
		(fp_line
			(start 0.504 0.248)
			(end -0.494 0.248)
			(stroke
				(width 0.15)
				(type solid)
			)
			(layer "F.Fab")
		)
		(fp_line
			(start -0.494 0.248)
			(end -0.494 -0.25)
			(stroke
				(width 0.15)
				(type solid)
			)
			(layer "F.Fab")
		)
		(pad "1" smd roundrect
			(at -0.48 0 90)
			(size 0.59 0.64)
			(layers "F.Cu" "F.Mask" "F.Paste")
			(roundrect_rratio 0.25)
			(net 1 "GND")
			(pintype "passive")
		)
		(pad "2" smd roundrect
			(at 0.48 0 90)
			(size 0.59 0.64)
			(layers "F.Cu" "F.Mask" "F.Paste")
			(roundrect_rratio 0.25)
			(net 5 "+5V")
			(pintype "passive")
		)
	)
	(footprint "antmicro-footprints:TP_SMD_0.75mm"
		(layer "F.Cu")
		(at 150.876 97.89)
		(property "Reference" "TP11"
			(at 0 -0.6 0)
			(layer "F.SilkS")
			(hide yes)
			(effects
				(font
					(size 0.7 0.7)
					(thickness 0.15)
				)
				(justify left bottom)
			)
		)
		(property "Value" "TP_0.75mm_SMD"
			(at 0 1.2 0)
			(layer "F.Fab")
			(effects
				(font
					(size 0.7 0.7)
					(thickness 0.15)
				)
				(justify left bottom)
			)
		)
		(property "Description" "SMT test point"
			(at 0 0 0)
			(layer "F.Fab")
			(hide yes)
			(effects
				(font
					(size 1.27 1.27)
					(thickness 0.15)
				)
			)
		)
		(property "Author" "Antmicro"
			(at 0 0 0)
			(layer "F.Fab")
			(hide yes)
			(effects
				(font
					(size 1 1)
					(thickness 0.15)
				)
			)
		)
		(property "License" "Apache-2.0"
			(at 0 0 0)
			(layer "F.Fab")
			(hide yes)
			(effects
				(font
					(size 1 1)
					(thickness 0.15)
				)
			)
		)
		(property "MPN" ""
			(at 0 0 0)
			(layer "F.Fab")
			(hide yes)
			(effects
				(font
					(size 1 1)
					(thickness 0.15)
				)
			)
		)
		(property "Manufacturer" ""
			(at 0 0 0)
			(layer "F.Fab")
			(hide yes)
			(effects
				(font
					(size 1 1)
					(thickness 0.15)
				)
			)
		)
		(sheetname "/Power/")
		(sheetfile "power.kicad_sch")
		(fp_circle
			(center 0 0)
			(end 0.475 0)
			(stroke
				(width 0.05)
				(type default)
			)
			(fill no)
			(layer "F.CrtYd")
		)
		(pad "1" smd circle
			(at 0 0)
			(size 0.75 0.75)
			(layers "F.Cu" "F.Mask")
			(net 5 "+5V")
			(pinfunction "1")
			(pintype "passive")
		)
	)
)
